(kicad_pcb
	(version 20260206)
	(generator "pcbnew")
	(generator_version "10.0")
	(general
		(thickness 1.6)
		(legacy_teardrops no)
	)
	(paper "A4")
	(title_block
		(title "01162023_DA0F0TEBIF0_F0T_Expander_BD_F_brd_V02_OCP.brd")
		(comment 1 "Grand Teton / footprints 9302-9308 of 9728")
	)
	(layers
		(0 "F.Cu" signal "TOP")
		(4 "In1.Cu" signal "GND")
		(6 "In2.Cu" signal "VCC")
		(8 "In3.Cu" signal "VCC1")
		(10 "In4.Cu" signal "GND1")
		(12 "In5.Cu" signal "IN1")
		(14 "In6.Cu" signal "GND2")
		(16 "In7.Cu" signal "IN2")
		(18 "In8.Cu" signal "GND3")
		(20 "In9.Cu" signal "IN3")
		(22 "In10.Cu" signal "GND4")
		(24 "In11.Cu" signal "IN4")
		(26 "In12.Cu" signal "GND5")
		(28 "In13.Cu" signal "IN5")
		(30 "In14.Cu" signal "GND6")
		(32 "In15.Cu" signal "IN6")
		(34 "In16.Cu" signal "GND7")
		(2 "B.Cu" signal "BOTTOM")
		(9 "F.Adhes" user "F.Adhesive")
		(11 "B.Adhes" user "B.Adhesive")
		(13 "F.Paste" user "Package Geometry/Pastemask Top")
		(15 "B.Paste" user "Package Geometry/Pastemask Bottom")
		(5 "F.SilkS" user "Ref Des/Silkscreen Top")
		(7 "B.SilkS" user "Ref Des/Silkscreen Bottom")
		(1 "F.Mask" user "Board Geometry/Soldermask Top")
		(3 "B.Mask" user "Board Geometry/Soldermask Bottom")
		(17 "Dwgs.User" user "User.Drawings")
		(19 "Cmts.User" user "User.Comments")
		(21 "Eco1.User" user "User.Eco1")
		(23 "Eco2.User" user "User.Eco2")
		(25 "Edge.Cuts" user "Board Geometry/Outline")
		(27 "Margin" user)
		(31 "F.CrtYd" user "Package Geometry/Place Bound Top")
		(29 "B.CrtYd" user "Package Geometry/Place Bound Bottom")
		(35 "F.Fab" user "Ref Des/Assembly Top")
		(33 "B.Fab" user "Ref Des/Assembly Bottom")
	)
	(footprint ""
		(layer "B.Cu")
		(at 378.587 -241.3 90)
		(property "Reference" "C2568"
			(at 0 0 90)
			(layer "B.SilkS")
			(hide yes)
			(effects
				(font
					(size 1.27 1.27)
				)
				(justify mirror)
			)
		)
		(property "Value" ""
			(at 0 0 90)
			(layer "B.Fab")
			(effects
				(font
					(size 1.27 1.27)
				)
				(justify mirror)
			)
		)
		(duplicate_pad_numbers_are_jumpers no)
		(fp_line
			(start 0.7874 -0.4064)
			(end -0.7874 -0.4064)
			(stroke
				(width 0.1524)
				(type default)
			)
			(layer "B.SilkS")
		)
		(fp_line
			(start -0.7874 -0.4064)
			(end -0.7874 0.4064)
			(stroke
				(width 0.1524)
				(type default)
			)
			(layer "B.SilkS")
		)
		(fp_line
			(start 0.7874 0.4064)
			(end 0.7874 -0.4064)
			(stroke
				(width 0.1524)
				(type default)
			)
			(layer "B.SilkS")
		)
		(fp_line
			(start -0.7874 0.4064)
			(end 0.7874 0.4064)
			(stroke
				(width 0.1524)
				(type default)
			)
			(layer "B.SilkS")
		)
		(fp_line
			(start 0.67945 -0.305054)
			(end 0.12065 -0.305054)
			(stroke
				(width 0.1)
				(type default)
			)
			(layer "B.Fab")
		)
		(fp_line
			(start 0.12065 -0.305054)
			(end 0.12065 -0.2794)
			(stroke
				(width 0.1)
				(type default)
			)
			(layer "B.Fab")
		)
		(fp_line
			(start -0.12065 -0.3048)
			(end -0.67945 -0.3048)
			(stroke
				(width 0.1)
				(type default)
			)
			(layer "B.Fab")
		)
		(fp_line
			(start -0.67945 -0.3048)
			(end -0.67945 0.3048)
			(stroke
				(width 0.1)
				(type default)
			)
			(layer "B.Fab")
		)
		(fp_line
			(start 0.12065 -0.2794)
			(end -0.12065 -0.2794)
			(stroke
				(width 0.1)
				(type default)
			)
			(layer "B.Fab")
		)
		(fp_line
			(start -0.12065 -0.2794)
			(end -0.12065 -0.3048)
			(stroke
				(width 0.1)
				(type default)
			)
			(layer "B.Fab")
		)
		(fp_line
			(start 0.12065 0.2794)
			(end 0.12065 0.3048)
			(stroke
				(width 0.1)
				(type default)
			)
			(layer "B.Fab")
		)
		(fp_line
			(start -0.120396 0.2794)
			(end 0.12065 0.2794)
			(stroke
				(width 0.1)
				(type default)
			)
			(layer "B.Fab")
		)
		(fp_line
			(start 0.67945 0.3048)
			(end 0.67945 -0.305054)
			(stroke
				(width 0.1)
				(type default)
			)
			(layer "B.Fab")
		)
		(fp_line
			(start 0.12065 0.3048)
			(end 0.67945 0.3048)
			(stroke
				(width 0.1)
				(type default)
			)
			(layer "B.Fab")
		)
		(fp_line
			(start -0.120396 0.3048)
			(end -0.120396 0.2794)
			(stroke
				(width 0.1)
				(type default)
			)
			(layer "B.Fab")
		)
		(fp_line
			(start -0.67945 0.3048)
			(end -0.120396 0.3048)
			(stroke
				(width 0.1)
				(type default)
			)
			(layer "B.Fab")
		)
		(pad "1" smd circle
			(at 0.40005 0 270)
			(size 0 0)
			(layers "B.Cu" "B.Mask" "B.Paste")
			(net "P3V3_AUX")
		)
		(pad "2" smd circle
			(at -0.40005 0 270)
			(size 0 0)
			(layers "B.Cu" "B.Mask" "B.Paste")
			(net "GND")
		)
	)
	(footprint ""
		(layer "B.Cu")
		(at 14.830298 -227.965 180)
		(property "Reference" "R3441"
			(at 0 0 0)
			(layer "B.SilkS")
			(hide yes)
			(effects
				(font
					(size 1.27 1.27)
				)
				(justify mirror)
			)
		)
		(property "Value" ""
			(at 0 0 0)
			(layer "B.Fab")
			(effects
				(font
					(size 1.27 1.27)
				)
				(justify mirror)
			)
		)
		(duplicate_pad_numbers_are_jumpers no)
		(fp_line
			(start 0.7874 0.4064)
			(end 0.7874 -0.4064)
			(stroke
				(width 0.1524)
				(type default)
			)
			(layer "B.SilkS")
		)
		(fp_line
			(start 0.7874 -0.4064)
			(end -0.7874 -0.4064)
			(stroke
				(width 0.1524)
				(type default)
			)
			(layer "B.SilkS")
		)
		(fp_line
			(start -0.7874 0.4064)
			(end 0.7874 0.4064)
			(stroke
				(width 0.1524)
				(type default)
			)
			(layer "B.SilkS")
		)
		(fp_line
			(start -0.7874 -0.4064)
			(end -0.7874 0.4064)
			(stroke
				(width 0.1524)
				(type default)
			)
			(layer "B.SilkS")
		)
		(fp_line
			(start 0.67945 0.3048)
			(end 0.67945 -0.305054)
			(stroke
				(width 0.1)
				(type default)
			)
			(layer "B.Fab")
		)
		(fp_line
			(start 0.67945 -0.305054)
			(end 0.12065 -0.305054)
			(stroke
				(width 0.1)
				(type default)
			)
			(layer "B.Fab")
		)
		(fp_line
			(start 0.12065 0.3048)
			(end 0.67945 0.3048)
			(stroke
				(width 0.1)
				(type default)
			)
			(layer "B.Fab")
		)
		(fp_line
			(start 0.12065 0.2794)
			(end 0.12065 0.3048)
			(stroke
				(width 0.1)
				(type default)
			)
			(layer "B.Fab")
		)
		(fp_line
			(start 0.12065 -0.2794)
			(end -0.12065 -0.2794)
			(stroke
				(width 0.1)
				(type default)
			)
			(layer "B.Fab")
		)
		(fp_line
			(start 0.12065 -0.305054)
			(end 0.12065 -0.2794)
			(stroke
				(width 0.1)
				(type default)
			)
			(layer "B.Fab")
		)
		(fp_line
			(start -0.120396 0.3048)
			(end -0.120396 0.2794)
			(stroke
				(width 0.1)
				(type default)
			)
			(layer "B.Fab")
		)
		(fp_line
			(start -0.120396 0.2794)
			(end 0.12065 0.2794)
			(stroke
				(width 0.1)
				(type default)
			)
			(layer "B.Fab")
		)
		(fp_line
			(start -0.12065 -0.2794)
			(end -0.12065 -0.3048)
			(stroke
				(width 0.1)
				(type default)
			)
			(layer "B.Fab")
		)
		(fp_line
			(start -0.12065 -0.3048)
			(end -0.67945 -0.3048)
			(stroke
				(width 0.1)
				(type default)
			)
			(layer "B.Fab")
		)
		(fp_line
			(start -0.67945 0.3048)
			(end -0.120396 0.3048)
			(stroke
				(width 0.1)
				(type default)
			)
			(layer "B.Fab")
		)
		(fp_line
			(start -0.67945 -0.3048)
			(end -0.67945 0.3048)
			(stroke
				(width 0.1)
				(type default)
			)
			(layer "B.Fab")
		)
		(pad "1" smd circle
			(at 0.40005 0)
			(size 0 0)
			(layers "B.Cu" "B.Mask" "B.Paste")
			(net "SPI_PEX0_SDIO2_R1")
		)
		(pad "2" smd circle
			(at -0.40005 0)
			(size 0 0)
			(layers "B.Cu" "B.Mask" "B.Paste")
			(net "GND")
		)
	)
	(footprint ""
		(layer "B.Cu")
		(at 425.841922 -100.056696 180)
		(property "Reference" "R383"
			(at 0 0 0)
			(layer "B.SilkS")
			(hide yes)
			(effects
				(font
					(size 1.27 1.27)
				)
				(justify mirror)
			)
		)
		(property "Value" ""
			(at 0 0 0)
			(layer "B.Fab")
			(effects
				(font
					(size 1.27 1.27)
				)
				(justify mirror)
			)
		)
		(duplicate_pad_numbers_are_jumpers no)
		(fp_line
			(start 0.7874 0.4064)
			(end 0.7874 -0.4064)
			(stroke
				(width 0.1524)
				(type default)
			)
			(layer "B.SilkS")
		)
		(fp_line
			(start 0.7874 -0.4064)
			(end -0.7874 -0.4064)
			(stroke
				(width 0.1524)
				(type default)
			)
			(layer "B.SilkS")
		)
		(fp_line
			(start -0.7874 0.4064)
			(end 0.7874 0.4064)
			(stroke
				(width 0.1524)
				(type default)
			)
			(layer "B.SilkS")
		)
		(fp_line
			(start -0.7874 -0.4064)
			(end -0.7874 0.4064)
			(stroke
				(width 0.1524)
				(type default)
			)
			(layer "B.SilkS")
		)
		(fp_line
			(start 0.67945 0.3048)
			(end 0.67945 -0.305054)
			(stroke
				(width 0.1)
				(type default)
			)
			(layer "B.Fab")
		)
		(fp_line
			(start 0.67945 -0.305054)
			(end 0.12065 -0.305054)
			(stroke
				(width 0.1)
				(type default)
			)
			(layer "B.Fab")
		)
		(fp_line
			(start 0.12065 0.3048)
			(end 0.67945 0.3048)
			(stroke
				(width 0.1)
				(type default)
			)
			(layer "B.Fab")
		)
		(fp_line
			(start 0.12065 0.2794)
			(end 0.12065 0.3048)
			(stroke
				(width 0.1)
				(type default)
			)
			(layer "B.Fab")
		)
		(fp_line
			(start 0.12065 -0.2794)
			(end -0.12065 -0.2794)
			(stroke
				(width 0.1)
				(type default)
			)
			(layer "B.Fab")
		)
		(fp_line
			(start 0.12065 -0.305054)
			(end 0.12065 -0.2794)
			(stroke
				(width 0.1)
				(type default)
			)
			(layer "B.Fab")
		)
		(fp_line
			(start -0.120396 0.3048)
			(end -0.120396 0.2794)
			(stroke
				(width 0.1)
				(type default)
			)
			(layer "B.Fab")
		)
		(fp_line
			(start -0.120396 0.2794)
			(end 0.12065 0.2794)
			(stroke
				(width 0.1)
				(type default)
			)
			(layer "B.Fab")
		)
		(fp_line
			(start -0.12065 -0.2794)
			(end -0.12065 -0.3048)
			(stroke
				(width 0.1)
				(type default)
			)
			(layer "B.Fab")
		)
		(fp_line
			(start -0.12065 -0.3048)
			(end -0.67945 -0.3048)
			(stroke
				(width 0.1)
				(type default)
			)
			(layer "B.Fab")
		)
		(fp_line
			(start -0.67945 0.3048)
			(end -0.120396 0.3048)
			(stroke
				(width 0.1)
				(type default)
			)
			(layer "B.Fab")
		)
		(fp_line
			(start -0.67945 -0.3048)
			(end -0.67945 0.3048)
			(stroke
				(width 0.1)
				(type default)
			)
			(layer "B.Fab")
		)
		(pad "1" smd circle
			(at 0.40005 0)
			(size 0 0)
			(layers "B.Cu" "B.Mask" "B.Paste")
			(net "NIC7_SLOT_ID0")
		)
		(pad "2" smd circle
			(at -0.40005 0)
			(size 0 0)
			(layers "B.Cu" "B.Mask" "B.Paste")
			(net "GND")
		)
	)
	(footprint ""
		(layer "B.Cu")
		(at 234.978956 -278.894286 -90)
		(property "Reference" "C4345"
			(at 0 0 90)
			(layer "B.SilkS")
			(hide yes)
			(effects
				(font
					(size 1.27 1.27)
				)
				(justify mirror)
			)
		)
		(property "Value" ""
			(at 0 0 90)
			(layer "B.Fab")
			(effects
				(font
					(size 1.27 1.27)
				)
				(justify mirror)
			)
		)
		(duplicate_pad_numbers_are_jumpers no)
		(fp_line
			(start -1.2954 0.5842)
			(end 1.2954 0.5842)
			(stroke
				(width 0.1524)
				(type default)
			)
			(layer "B.SilkS")
		)
		(fp_line
			(start 1.2954 0.5842)
			(end 1.2954 -0.5842)
			(stroke
				(width 0.1524)
				(type default)
			)
			(layer "B.SilkS")
		)
		(fp_line
			(start -1.2954 -0.5842)
			(end -1.2954 0.5842)
			(stroke
				(width 0.1524)
				(type default)
			)
			(layer "B.SilkS")
		)
		(fp_line
			(start 1.2954 -0.5842)
			(end -1.2954 -0.5842)
			(stroke
				(width 0.1524)
				(type default)
			)
			(layer "B.SilkS")
		)
		(fp_line
			(start -0.8636 0.4572)
			(end 0.8636 0.4572)
			(stroke
				(width 0.1)
				(type default)
			)
			(layer "B.Fab")
		)
		(fp_line
			(start 0.8636 0.4572)
			(end 0.8636 0.4064)
			(stroke
				(width 0.1)
				(type default)
			)
			(layer "B.Fab")
		)
		(fp_line
			(start -1.1938 0.4064)
			(end -0.8636 0.4064)
			(stroke
				(width 0.1)
				(type default)
			)
			(layer "B.Fab")
		)
		(fp_line
			(start -0.8636 0.4064)
			(end -0.8636 0.4572)
			(stroke
				(width 0.1)
				(type default)
			)
			(layer "B.Fab")
		)
		(fp_line
			(start 0.8636 0.4064)
			(end 1.1938 0.4064)
			(stroke
				(width 0.1)
				(type default)
			)
			(layer "B.Fab")
		)
		(fp_line
			(start 1.1938 0.4064)
			(end 1.1938 -0.4064)
			(stroke
				(width 0.1)
				(type default)
			)
			(layer "B.Fab")
		)
		(fp_line
			(start -1.1938 -0.4064)
			(end -1.1938 0.4064)
			(stroke
				(width 0.1)
				(type default)
			)
			(layer "B.Fab")
		)
		(fp_line
			(start -0.8636 -0.4064)
			(end -1.1938 -0.4064)
			(stroke
				(width 0.1)
				(type default)
			)
			(layer "B.Fab")
		)
		(fp_line
			(start 0.8636 -0.4064)
			(end 0.8636 -0.4572)
			(stroke
				(width 0.1)
				(type default)
			)
			(layer "B.Fab")
		)
		(fp_line
			(start 1.1938 -0.4064)
			(end 0.8636 -0.4064)
			(stroke
				(width 0.1)
				(type default)
			)
			(layer "B.Fab")
		)
		(fp_line
			(start -0.8636 -0.4572)
			(end -0.8636 -0.4064)
			(stroke
				(width 0.1)
				(type default)
			)
			(layer "B.Fab")
		)
		(fp_line
			(start 0.8636 -0.4572)
			(end -0.8636 -0.4572)
			(stroke
				(width 0.1)
				(type default)
			)
			(layer "B.Fab")
		)
		(pad "1" smd rect
			(at 0.7366 0 180)
			(size 0.7112 0.8128)
			(layers "B.Cu" "B.Mask" "B.Paste")
			(net "P1V25_PEX2")
		)
		(pad "2" smd rect
			(at -0.7366 0 180)
			(size 0.7112 0.8128)
			(layers "B.Cu" "B.Mask" "B.Paste")
			(net "GND")
		)
	)
	(footprint ""
		(layer "B.Cu")
		(at 191.81699 -295.42486)
		(property "Reference" "C3075"
			(at 0 0 0)
			(layer "B.SilkS")
			(hide yes)
			(effects
				(font
					(size 1.27 1.27)
				)
				(justify mirror)
			)
		)
		(property "Value" ""
			(at 0 0 0)
			(layer "B.Fab")
			(effects
				(font
					(size 1.27 1.27)
				)
				(justify mirror)
			)
		)
		(duplicate_pad_numbers_are_jumpers no)
		(fp_line
			(start -1.2954 -0.5842)
			(end -1.2954 0.5842)
			(stroke
				(width 0.1524)
				(type default)
			)
			(layer "B.SilkS")
		)
		(fp_line
			(start -1.2954 0.5842)
			(end 1.2954 0.5842)
			(stroke
				(width 0.1524)
				(type default)
			)
			(layer "B.SilkS")
		)
		(fp_line
			(start 1.2954 -0.5842)
			(end -1.2954 -0.5842)
			(stroke
				(width 0.1524)
				(type default)
			)
			(layer "B.SilkS")
		)
		(fp_line
			(start 1.2954 0.5842)
			(end 1.2954 -0.5842)
			(stroke
				(width 0.1524)
				(type default)
			)
			(layer "B.SilkS")
		)
		(fp_line
			(start -1.1938 -0.4064)
			(end -1.1938 0.4064)
			(stroke
				(width 0.1)
				(type default)
			)
			(layer "B.Fab")
		)
		(fp_line
			(start -1.1938 0.4064)
			(end -0.8636 0.4064)
			(stroke
				(width 0.1)
				(type default)
			)
			(layer "B.Fab")
		)
		(fp_line
			(start -0.8636 -0.4572)
			(end -0.8636 -0.4064)
			(stroke
				(width 0.1)
				(type default)
			)
			(layer "B.Fab")
		)
		(fp_line
			(start -0.8636 -0.4064)
			(end -1.1938 -0.4064)
			(stroke
				(width 0.1)
				(type default)
			)
			(layer "B.Fab")
		)
		(fp_line
			(start -0.8636 0.4064)
			(end -0.8636 0.4572)
			(stroke
				(width 0.1)
				(type default)
			)
			(layer "B.Fab")
		)
		(fp_line
			(start -0.8636 0.4572)
			(end 0.8636 0.4572)
			(stroke
				(width 0.1)
				(type default)
			)
			(layer "B.Fab")
		)
		(fp_line
			(start 0.8636 -0.4572)
			(end -0.8636 -0.4572)
			(stroke
				(width 0.1)
				(type default)
			)
			(layer "B.Fab")
		)
		(fp_line
			(start 0.8636 -0.4064)
			(end 0.8636 -0.4572)
			(stroke
				(width 0.1)
				(type default)
			)
			(layer "B.Fab")
		)
		(fp_line
			(start 0.8636 0.4064)
			(end 1.1938 0.4064)
			(stroke
				(width 0.1)
				(type default)
			)
			(layer "B.Fab")
		)
		(fp_line
			(start 0.8636 0.4572)
			(end 0.8636 0.4064)
			(stroke
				(width 0.1)
				(type default)
			)
			(layer "B.Fab")
		)
		(fp_line
			(start 1.1938 -0.4064)
			(end 0.8636 -0.4064)
			(stroke
				(width 0.1)
				(type default)
			)
			(layer "B.Fab")
		)
		(fp_line
			(start 1.1938 0.4064)
			(end 1.1938 -0.4064)
			(stroke
				(width 0.1)
				(type default)
			)
			(layer "B.Fab")
		)
		(pad "1" smd rect
			(at 0.7366 0 270)
			(size 0.7112 0.8128)
			(layers "B.Cu" "B.Mask" "B.Paste")
			(net "P1V25_PEX1")
		)
		(pad "2" smd rect
			(at -0.7366 0 270)
			(size 0.7112 0.8128)
			(layers "B.Cu" "B.Mask" "B.Paste")
			(net "GND")
		)
	)
	(footprint ""
		(layer "B.Cu")
		(at 165.655244 -154.0256)
		(property "Reference" "R123"
			(at 0 0 0)
			(layer "B.SilkS")
			(hide yes)
			(effects
				(font
					(size 1.27 1.27)
				)
				(justify mirror)
			)
		)
		(property "Value" ""
			(at 0 0 0)
			(layer "B.Fab")
			(effects
				(font
					(size 1.27 1.27)
				)
				(justify mirror)
			)
		)
		(duplicate_pad_numbers_are_jumpers no)
		(fp_line
			(start -0.7874 -0.4064)
			(end -0.7874 0.4064)
			(stroke
				(width 0.1524)
				(type default)
			)
			(layer "B.SilkS")
		)
		(fp_line
			(start -0.7874 0.4064)
			(end 0.7874 0.4064)
			(stroke
				(width 0.1524)
				(type default)
			)
			(layer "B.SilkS")
		)
		(fp_line
			(start 0.7874 -0.4064)
			(end -0.7874 -0.4064)
			(stroke
				(width 0.1524)
				(type default)
			)
			(layer "B.SilkS")
		)
		(fp_line
			(start 0.7874 0.4064)
			(end 0.7874 -0.4064)
			(stroke
				(width 0.1524)
				(type default)
			)
			(layer "B.SilkS")
		)
		(fp_line
			(start -0.67945 -0.3048)
			(end -0.67945 0.3048)
			(stroke
				(width 0.1)
				(type default)
			)
			(layer "B.Fab")
		)
		(fp_line
			(start -0.67945 0.3048)
			(end -0.120396 0.3048)
			(stroke
				(width 0.1)
				(type default)
			)
			(layer "B.Fab")
		)
		(fp_line
			(start -0.12065 -0.3048)
			(end -0.67945 -0.3048)
			(stroke
				(width 0.1)
				(type default)
			)
			(layer "B.Fab")
		)
		(fp_line
			(start -0.12065 -0.2794)
			(end -0.12065 -0.3048)
			(stroke
				(width 0.1)
				(type default)
			)
			(layer "B.Fab")
		)
		(fp_line
			(start -0.120396 0.2794)
			(end 0.12065 0.2794)
			(stroke
				(width 0.1)
				(type default)
			)
			(layer "B.Fab")
		)
		(fp_line
			(start -0.120396 0.3048)
			(end -0.120396 0.2794)
			(stroke
				(width 0.1)
				(type default)
			)
			(layer "B.Fab")
		)
		(fp_line
			(start 0.12065 -0.305054)
			(end 0.12065 -0.2794)
			(stroke
				(width 0.1)
				(type default)
			)
			(layer "B.Fab")
		)
		(fp_line
			(start 0.12065 -0.2794)
			(end -0.12065 -0.2794)
			(stroke
				(width 0.1)
				(type default)
			)
			(layer "B.Fab")
		)
		(fp_line
			(start 0.12065 0.2794)
			(end 0.12065 0.3048)
			(stroke
				(width 0.1)
				(type default)
			)
			(layer "B.Fab")
		)
		(fp_line
			(start 0.12065 0.3048)
			(end 0.67945 0.3048)
			(stroke
				(width 0.1)
				(type default)
			)
			(layer "B.Fab")
		)
		(fp_line
			(start 0.67945 -0.305054)
			(end 0.12065 -0.305054)
			(stroke
				(width 0.1)
				(type default)
			)
			(layer "B.Fab")
		)
		(fp_line
			(start 0.67945 0.3048)
			(end 0.67945 -0.305054)
			(stroke
				(width 0.1)
				(type default)
			)
			(layer "B.Fab")
		)
		(pad "1" smd circle
			(at 0.40005 0 180)
			(size 0 0)
			(layers "B.Cu" "B.Mask" "B.Paste")
			(net "NCSI_NIC2_TX_EN")
		)
		(pad "2" smd circle
			(at -0.40005 0 180)
			(size 0 0)
			(layers "B.Cu" "B.Mask" "B.Paste")
			(net "GND")
		)
	)
	(footprint ""
		(layer "B.Cu")
		(at 8.861044 -277.83155 180)
		(property "Reference" "C4222"
			(at 0 0 0)
			(layer "B.SilkS")
			(hide yes)
			(effects
				(font
					(size 1.27 1.27)
				)
				(justify mirror)
			)
		)
		(property "Value" ""
			(at 0 0 0)
			(layer "B.Fab")
			(effects
				(font
					(size 1.27 1.27)
				)
				(justify mirror)
			)
		)
		(duplicate_pad_numbers_are_jumpers no)
		(fp_line
			(start 0.299974 0.150114)
			(end 0.299974 -0.150114)
			(stroke
				(width 0.1)
				(type default)
			)
			(layer "B.Fab")
		)
		(fp_line
			(start 0.299974 -0.150114)
			(end -0.299974 -0.150114)
			(stroke
				(width 0.1)
				(type default)
			)
			(layer "B.Fab")
		)
		(fp_line
			(start -0.299974 0.150114)
			(end 0.299974 0.150114)
			(stroke
				(width 0.1)
				(type default)
			)
			(layer "B.Fab")
		)
		(fp_line
			(start -0.299974 -0.150114)
			(end -0.299974 0.150114)
			(stroke
				(width 0.1)
				(type default)
			)
			(layer "B.Fab")
		)
		(pad "1" smd rect
			(at 0.2667 0)
			(size 0.3048 0.381)
			(layers "B.Cu" "B.Mask" "B.Paste")
			(net "P1V25_PEX0")
		)
		(pad "2" smd rect
			(at -0.2667 0)
			(size 0.3048 0.381)
			(layers "B.Cu" "B.Mask" "B.Paste")
			(net "GND")
		)
	)
)
